(kicad_pcb
	(version 20260206)
	(generator "pcbnew")
	(generator_version "10.0")
	(general
		(thickness 1.6)
		(legacy_teardrops no)
	)
	(paper "A4")
	(title_block
		(title "01162023_DA0F0TEBIF0_F0T_Expander_BD_F_brd_V02_OCP.brd")
		(comment 1 "Grand Teton / footprint 6602 of 9728 (PEX1), pads 1768-1882 of 2397")
	)
	(layers
		(0 "F.Cu" signal "TOP")
		(4 "In1.Cu" signal "GND")
		(6 "In2.Cu" signal "VCC")
		(8 "In3.Cu" signal "VCC1")
		(10 "In4.Cu" signal "GND1")
		(12 "In5.Cu" signal "IN1")
		(14 "In6.Cu" signal "GND2")
		(16 "In7.Cu" signal "IN2")
		(18 "In8.Cu" signal "GND3")
		(20 "In9.Cu" signal "IN3")
		(22 "In10.Cu" signal "GND4")
		(24 "In11.Cu" signal "IN4")
		(26 "In12.Cu" signal "GND5")
		(28 "In13.Cu" signal "IN5")
		(30 "In14.Cu" signal "GND6")
		(32 "In15.Cu" signal "IN6")
		(34 "In16.Cu" signal "GND7")
		(2 "B.Cu" signal "BOTTOM")
		(9 "F.Adhes" user "F.Adhesive")
		(11 "B.Adhes" user "B.Adhesive")
		(13 "F.Paste" user "Package Geometry/Pastemask Top")
		(15 "B.Paste" user "Package Geometry/Pastemask Bottom")
		(5 "F.SilkS" user "Ref Des/Silkscreen Top")
		(7 "B.SilkS" user "Ref Des/Silkscreen Bottom")
		(1 "F.Mask" user "Board Geometry/Soldermask Top")
		(3 "B.Mask" user "Board Geometry/Soldermask Bottom")
		(17 "Dwgs.User" user "User.Drawings")
		(19 "Cmts.User" user "User.Comments")
		(21 "Eco1.User" user "User.Eco1")
		(23 "Eco2.User" user "User.Eco2")
		(25 "Edge.Cuts" user "Board Geometry/Outline")
		(27 "Margin" user)
		(31 "F.CrtYd" user "Package Geometry/Place Bound Top")
		(29 "B.CrtYd" user "Package Geometry/Place Bound Bottom")
		(35 "F.Fab" user "Ref Des/Assembly Top")
		(33 "B.Fab" user "Ref Des/Assembly Bottom")
	)
	(footprint ""
		(layer "F.Cu")
		(at 175.749966 -295.89984)
		(property "Reference" "PEX1"
			(at -3.353562 35.593274 0)
			(unlocked yes)
			(layer "F.SilkS")
			(effects
				(font
					(size 2.032 1.524)
					(thickness 0.1524)
				)
				(justify left)
			)
		)
		(property "Value" ""
			(at 0 0 0)
			(layer "F.Fab")
			(effects
				(font
					(size 1.27 1.27)
				)
			)
		)
		(duplicate_pad_numbers_are_jumpers no)
		(pad "H8" smd circle
			(at -16.150082 -16.150082)
			(size 0.4572 0.4572)
			(layers "F.Cu" "F.Mask" "F.Paste")
			(net "P5E_PEX1_STN6_TX_DN<111>")
		)
		(pad "H9" smd circle
			(at -15.200122 -16.150082)
			(size 0.4572 0.4572)
			(layers "F.Cu" "F.Mask" "F.Paste")
			(net "GND")
		)
		(pad "H10" smd circle
			(at -14.249908 -16.150082)
			(size 0.4572 0.4572)
			(layers "F.Cu" "F.Mask" "F.Paste")
			(net "P5E_PEX1_STN6_TX_DN<109>")
		)
		(pad "H11" smd circle
			(at -13.299948 -16.150082)
			(size 0.4572 0.4572)
			(layers "F.Cu" "F.Mask" "F.Paste")
			(net "GND")
		)
		(pad "H12" smd circle
			(at -12.349988 -16.150082)
			(size 0.4572 0.4572)
			(layers "F.Cu" "F.Mask" "F.Paste")
			(net "P5E_PEX1_STN6_TX_DN<107>")
		)
		(pad "H13" smd circle
			(at -11.400028 -16.150082)
			(size 0.4572 0.4572)
			(layers "F.Cu" "F.Mask" "F.Paste")
			(net "GND")
		)
		(pad "H14" smd circle
			(at -10.450068 -16.150082)
			(size 0.4572 0.4572)
			(layers "F.Cu" "F.Mask" "F.Paste")
			(net "P5E_PEX1_STN6_TX_DN<105>")
		)
		(pad "H15" smd circle
			(at -9.500108 -16.150082)
			(size 0.4572 0.4572)
			(layers "F.Cu" "F.Mask" "F.Paste")
			(net "GND")
		)
		(pad "H16" smd circle
			(at -8.549894 -16.150082)
			(size 0.4572 0.4572)
			(layers "F.Cu" "F.Mask" "F.Paste")
			(net "P5E_PEX1_STN6_TX_DN<103>")
		)
		(pad "H17" smd circle
			(at -7.599934 -16.150082)
			(size 0.4572 0.4572)
			(layers "F.Cu" "F.Mask" "F.Paste")
			(net "GND")
		)
		(pad "H18" smd circle
			(at -6.649974 -16.150082)
			(size 0.4572 0.4572)
			(layers "F.Cu" "F.Mask" "F.Paste")
			(net "P5E_PEX1_STN6_TX_DN<101>")
		)
		(pad "H19" smd circle
			(at -5.700014 -16.150082)
			(size 0.4572 0.4572)
			(layers "F.Cu" "F.Mask" "F.Paste")
			(net "GND")
		)
		(pad "H20" smd circle
			(at -4.750054 -16.150082)
			(size 0.4572 0.4572)
			(layers "F.Cu" "F.Mask" "F.Paste")
			(net "P5E_PEX1_STN6_TX_DN<99>")
		)
		(pad "H21" smd circle
			(at -3.800094 -16.150082)
			(size 0.4572 0.4572)
			(layers "F.Cu" "F.Mask" "F.Paste")
			(net "GND")
		)
		(pad "H22" smd circle
			(at -2.84988 -16.150082)
			(size 0.4572 0.4572)
			(layers "F.Cu" "F.Mask" "F.Paste")
			(net "P5E_PEX1_STN6_TX_DN<97>")
		)
		(pad "H23" smd circle
			(at -1.89992 -16.150082)
			(size 0.4572 0.4572)
			(layers "F.Cu" "F.Mask" "F.Paste")
			(net "GND")
		)
		(pad "H24" smd circle
			(at -0.94996 -16.150082)
			(size 0.4572 0.4572)
			(layers "F.Cu" "F.Mask" "F.Paste")
			(net "P5E_PEX1_STN5_TX_DN<80>")
		)
		(pad "H25" smd circle
			(at 0 -16.150082)
			(size 0.4572 0.4572)
			(layers "F.Cu" "F.Mask" "F.Paste")
			(net "GND")
		)
		(pad "H26" smd circle
			(at 0.94996 -16.150082)
			(size 0.4572 0.4572)
			(layers "F.Cu" "F.Mask" "F.Paste")
			(net "P5E_PEX1_STN5_TX_DN<82>")
		)
		(pad "H27" smd circle
			(at 1.89992 -16.150082)
			(size 0.4572 0.4572)
			(layers "F.Cu" "F.Mask" "F.Paste")
			(net "GND")
		)
		(pad "H28" smd circle
			(at 2.84988 -16.150082)
			(size 0.4572 0.4572)
			(layers "F.Cu" "F.Mask" "F.Paste")
			(net "P5E_PEX1_STN5_TX_DN<84>")
		)
		(pad "H29" smd circle
			(at 3.800094 -16.150082)
			(size 0.4572 0.4572)
			(layers "F.Cu" "F.Mask" "F.Paste")
			(net "GND")
		)
		(pad "H30" smd circle
			(at 4.750054 -16.150082)
			(size 0.4572 0.4572)
			(layers "F.Cu" "F.Mask" "F.Paste")
			(net "P5E_PEX1_STN5_TX_DN<86>")
		)
		(pad "H31" smd circle
			(at 5.700014 -16.150082)
			(size 0.4572 0.4572)
			(layers "F.Cu" "F.Mask" "F.Paste")
			(net "GND")
		)
		(pad "H32" smd circle
			(at 6.649974 -16.150082)
			(size 0.4572 0.4572)
			(layers "F.Cu" "F.Mask" "F.Paste")
			(net "P5E_PEX1_STN5_TX_DN<88>")
		)
		(pad "H33" smd circle
			(at 7.599934 -16.150082)
			(size 0.4572 0.4572)
			(layers "F.Cu" "F.Mask" "F.Paste")
			(net "GND")
		)
		(pad "H34" smd circle
			(at 8.549894 -16.150082)
			(size 0.4572 0.4572)
			(layers "F.Cu" "F.Mask" "F.Paste")
			(net "P5E_PEX1_STN5_TX_DN<90>")
		)
		(pad "H35" smd circle
			(at 9.500108 -16.150082)
			(size 0.4572 0.4572)
			(layers "F.Cu" "F.Mask" "F.Paste")
			(net "GND")
		)
		(pad "H36" smd circle
			(at 10.450068 -16.150082)
			(size 0.4572 0.4572)
			(layers "F.Cu" "F.Mask" "F.Paste")
			(net "P5E_PEX1_STN5_TX_DN<92>")
		)
		(pad "H37" smd circle
			(at 11.400028 -16.150082)
			(size 0.4572 0.4572)
			(layers "F.Cu" "F.Mask" "F.Paste")
			(net "GND")
		)
		(pad "H38" smd circle
			(at 12.349988 -16.150082)
			(size 0.4572 0.4572)
			(layers "F.Cu" "F.Mask" "F.Paste")
			(net "P5E_PEX1_STN5_TX_DN<94>")
		)
		(pad "H39" smd circle
			(at 13.299948 -16.150082)
			(size 0.4572 0.4572)
			(layers "F.Cu" "F.Mask" "F.Paste")
			(net "GND")
		)
		(pad "H40" smd circle
			(at 14.249908 -16.150082)
			(size 0.4572 0.4572)
			(layers "F.Cu" "F.Mask" "F.Paste")
			(net "P5E_PEX1_STN4_TX_DN<79>")
		)
		(pad "H41" smd circle
			(at 15.200122 -16.150082)
			(size 0.4572 0.4572)
			(layers "F.Cu" "F.Mask" "F.Paste")
			(net "GND")
		)
		(pad "H42" smd circle
			(at 16.150082 -16.150082)
			(size 0.4572 0.4572)
			(layers "F.Cu" "F.Mask" "F.Paste")
			(net "P5E_PEX1_STN4_TX_DN<77>")
		)
		(pad "H43" smd circle
			(at 17.100042 -16.150082)
			(size 0.4572 0.4572)
			(layers "F.Cu" "F.Mask" "F.Paste")
			(net "GND")
		)
		(pad "H44" smd circle
			(at 18.050002 -16.150082)
			(size 0.4572 0.4572)
			(layers "F.Cu" "F.Mask" "F.Paste")
			(net "P5E_PEX1_STN4_TX_DN<75>")
		)
		(pad "H45" smd circle
			(at 18.999962 -16.150082)
			(size 0.4572 0.4572)
			(layers "F.Cu" "F.Mask" "F.Paste")
			(net "GND")
		)
		(pad "H46" smd circle
			(at 19.949922 -16.150082)
			(size 0.4572 0.4572)
			(layers "F.Cu" "F.Mask" "F.Paste")
			(net "P5E_PEX1_STN4_TX_DN<73>")
		)
		(pad "H47" smd circle
			(at 20.899882 -16.150082)
			(size 0.4572 0.4572)
			(layers "F.Cu" "F.Mask" "F.Paste")
			(net "GND")
		)
		(pad "H48" smd circle
			(at 21.850096 -16.150082)
			(size 0.4572 0.4572)
			(layers "F.Cu" "F.Mask" "F.Paste")
			(net "P5E_PEX1_STN4_TX_DP<70>")
		)
		(pad "H49" smd circle
			(at 22.800056 -16.150082)
			(size 0.4572 0.4572)
			(layers "F.Cu" "F.Mask" "F.Paste")
			(net "P5E_PEX1_STN4_TX_DN<70>")
		)
		(pad "J1" smd circle
			(at -22.800056 -15.200122)
			(size 0.4572 0.4572)
			(layers "F.Cu" "F.Mask" "F.Paste")
			(net "GND")
		)
		(pad "J2" smd circle
			(at -21.850096 -15.200122)
			(size 0.4572 0.4572)
			(layers "F.Cu" "F.Mask" "F.Paste")
			(net "GND")
		)
		(pad "J3" smd circle
			(at -20.899882 -15.200122)
			(size 0.4572 0.4572)
			(layers "F.Cu" "F.Mask" "F.Paste")
			(net "GND")
		)
		(pad "J4" smd circle
			(at -19.949922 -15.200122)
			(size 0.4572 0.4572)
			(layers "F.Cu" "F.Mask" "F.Paste")
			(net "P5E_PEX1_STN7_TX_DP<124>")
		)
		(pad "J5" smd circle
			(at -18.999962 -15.200122)
			(size 0.4572 0.4572)
			(layers "F.Cu" "F.Mask" "F.Paste")
			(net "GND")
		)
		(pad "J6" smd circle
			(at -18.050002 -15.200122)
			(size 0.4572 0.4572)
			(layers "F.Cu" "F.Mask" "F.Paste")
			(net "P5E_PEX1_STN7_TX_DP<126>")
		)
		(pad "J7" smd circle
			(at -17.100042 -15.200122)
			(size 0.4572 0.4572)
			(layers "F.Cu" "F.Mask" "F.Paste")
			(net "GND")
		)
		(pad "J8" smd circle
			(at -16.150082 -15.200122)
			(size 0.4572 0.4572)
			(layers "F.Cu" "F.Mask" "F.Paste")
			(net "P5E_PEX1_STN6_TX_DP<111>")
		)
		(pad "J9" smd circle
			(at -15.200122 -15.200122)
			(size 0.4572 0.4572)
			(layers "F.Cu" "F.Mask" "F.Paste")
			(net "GND")
		)
		(pad "J10" smd circle
			(at -14.249908 -15.200122)
			(size 0.4572 0.4572)
			(layers "F.Cu" "F.Mask" "F.Paste")
			(net "P5E_PEX1_STN6_TX_DP<109>")
		)
		(pad "J11" smd circle
			(at -13.299948 -15.200122)
			(size 0.4572 0.4572)
			(layers "F.Cu" "F.Mask" "F.Paste")
			(net "GND")
		)
		(pad "J12" smd circle
			(at -12.349988 -15.200122)
			(size 0.4572 0.4572)
			(layers "F.Cu" "F.Mask" "F.Paste")
			(net "P5E_PEX1_STN6_TX_DP<107>")
		)
		(pad "J13" smd circle
			(at -11.400028 -15.200122)
			(size 0.4572 0.4572)
			(layers "F.Cu" "F.Mask" "F.Paste")
			(net "GND")
		)
		(pad "J14" smd circle
			(at -10.450068 -15.200122)
			(size 0.4572 0.4572)
			(layers "F.Cu" "F.Mask" "F.Paste")
			(net "P5E_PEX1_STN6_TX_DP<105>")
		)
		(pad "J15" smd circle
			(at -9.500108 -15.200122)
			(size 0.4572 0.4572)
			(layers "F.Cu" "F.Mask" "F.Paste")
			(net "GND")
		)
		(pad "J16" smd circle
			(at -8.549894 -15.200122)
			(size 0.4572 0.4572)
			(layers "F.Cu" "F.Mask" "F.Paste")
			(net "P5E_PEX1_STN6_TX_DP<103>")
		)
		(pad "J17" smd circle
			(at -7.599934 -15.200122)
			(size 0.4572 0.4572)
			(layers "F.Cu" "F.Mask" "F.Paste")
			(net "GND")
		)
		(pad "J18" smd circle
			(at -6.649974 -15.200122)
			(size 0.4572 0.4572)
			(layers "F.Cu" "F.Mask" "F.Paste")
			(net "P5E_PEX1_STN6_TX_DP<101>")
		)
		(pad "J19" smd circle
			(at -5.700014 -15.200122)
			(size 0.4572 0.4572)
			(layers "F.Cu" "F.Mask" "F.Paste")
			(net "GND")
		)
		(pad "J20" smd circle
			(at -4.750054 -15.200122)
			(size 0.4572 0.4572)
			(layers "F.Cu" "F.Mask" "F.Paste")
			(net "P5E_PEX1_STN6_TX_DP<99>")
		)
		(pad "J21" smd circle
			(at -3.800094 -15.200122)
			(size 0.4572 0.4572)
			(layers "F.Cu" "F.Mask" "F.Paste")
			(net "GND")
		)
		(pad "J22" smd circle
			(at -2.84988 -15.200122)
			(size 0.4572 0.4572)
			(layers "F.Cu" "F.Mask" "F.Paste")
			(net "P5E_PEX1_STN6_TX_DP<97>")
		)
		(pad "J23" smd circle
			(at -1.89992 -15.200122)
			(size 0.4572 0.4572)
			(layers "F.Cu" "F.Mask" "F.Paste")
			(net "GND")
		)
		(pad "J24" smd circle
			(at -0.94996 -15.200122)
			(size 0.4572 0.4572)
			(layers "F.Cu" "F.Mask" "F.Paste")
			(net "P5E_PEX1_STN5_TX_DP<80>")
		)
		(pad "J25" smd circle
			(at 0 -15.200122)
			(size 0.4572 0.4572)
			(layers "F.Cu" "F.Mask" "F.Paste")
			(net "GND")
		)
		(pad "J26" smd circle
			(at 0.94996 -15.200122)
			(size 0.4572 0.4572)
			(layers "F.Cu" "F.Mask" "F.Paste")
			(net "P5E_PEX1_STN5_TX_DP<82>")
		)
		(pad "J27" smd circle
			(at 1.89992 -15.200122)
			(size 0.4572 0.4572)
			(layers "F.Cu" "F.Mask" "F.Paste")
			(net "GND")
		)
		(pad "J28" smd circle
			(at 2.84988 -15.200122)
			(size 0.4572 0.4572)
			(layers "F.Cu" "F.Mask" "F.Paste")
			(net "P5E_PEX1_STN5_TX_DP<84>")
		)
		(pad "J29" smd circle
			(at 3.800094 -15.200122)
			(size 0.4572 0.4572)
			(layers "F.Cu" "F.Mask" "F.Paste")
			(net "GND")
		)
		(pad "J30" smd circle
			(at 4.750054 -15.200122)
			(size 0.4572 0.4572)
			(layers "F.Cu" "F.Mask" "F.Paste")
			(net "P5E_PEX1_STN5_TX_DP<86>")
		)
		(pad "J31" smd circle
			(at 5.700014 -15.200122)
			(size 0.4572 0.4572)
			(layers "F.Cu" "F.Mask" "F.Paste")
			(net "GND")
		)
		(pad "J32" smd circle
			(at 6.649974 -15.200122)
			(size 0.4572 0.4572)
			(layers "F.Cu" "F.Mask" "F.Paste")
			(net "P5E_PEX1_STN5_TX_DP<88>")
		)
		(pad "J33" smd circle
			(at 7.599934 -15.200122)
			(size 0.4572 0.4572)
			(layers "F.Cu" "F.Mask" "F.Paste")
			(net "GND")
		)
		(pad "J34" smd circle
			(at 8.549894 -15.200122)
			(size 0.4572 0.4572)
			(layers "F.Cu" "F.Mask" "F.Paste")
			(net "P5E_PEX1_STN5_TX_DP<90>")
		)
		(pad "J35" smd circle
			(at 9.500108 -15.200122)
			(size 0.4572 0.4572)
			(layers "F.Cu" "F.Mask" "F.Paste")
			(net "GND")
		)
		(pad "J36" smd circle
			(at 10.450068 -15.200122)
			(size 0.4572 0.4572)
			(layers "F.Cu" "F.Mask" "F.Paste")
			(net "P5E_PEX1_STN5_TX_DP<92>")
		)
		(pad "J37" smd circle
			(at 11.400028 -15.200122)
			(size 0.4572 0.4572)
			(layers "F.Cu" "F.Mask" "F.Paste")
			(net "GND")
		)
		(pad "J38" smd circle
			(at 12.349988 -15.200122)
			(size 0.4572 0.4572)
			(layers "F.Cu" "F.Mask" "F.Paste")
			(net "P5E_PEX1_STN5_TX_DP<94>")
		)
		(pad "J39" smd circle
			(at 13.299948 -15.200122)
			(size 0.4572 0.4572)
			(layers "F.Cu" "F.Mask" "F.Paste")
			(net "GND")
		)
		(pad "J40" smd circle
			(at 14.249908 -15.200122)
			(size 0.4572 0.4572)
			(layers "F.Cu" "F.Mask" "F.Paste")
			(net "P5E_PEX1_STN4_TX_DP<79>")
		)
		(pad "J41" smd circle
			(at 15.200122 -15.200122)
			(size 0.4572 0.4572)
			(layers "F.Cu" "F.Mask" "F.Paste")
			(net "GND")
		)
		(pad "J42" smd circle
			(at 16.150082 -15.200122)
			(size 0.4572 0.4572)
			(layers "F.Cu" "F.Mask" "F.Paste")
			(net "P5E_PEX1_STN4_TX_DP<77>")
		)
		(pad "J43" smd circle
			(at 17.100042 -15.200122)
			(size 0.4572 0.4572)
			(layers "F.Cu" "F.Mask" "F.Paste")
			(net "GND")
		)
		(pad "J44" smd circle
			(at 18.050002 -15.200122)
			(size 0.4572 0.4572)
			(layers "F.Cu" "F.Mask" "F.Paste")
			(net "P5E_PEX1_STN4_TX_DP<75>")
		)
		(pad "J45" smd circle
			(at 18.999962 -15.200122)
			(size 0.4572 0.4572)
			(layers "F.Cu" "F.Mask" "F.Paste")
			(net "GND")
		)
		(pad "J46" smd circle
			(at 19.949922 -15.200122)
			(size 0.4572 0.4572)
			(layers "F.Cu" "F.Mask" "F.Paste")
			(net "P5E_PEX1_STN4_TX_DP<73>")
		)
		(pad "J47" smd circle
			(at 20.899882 -15.200122)
			(size 0.4572 0.4572)
			(layers "F.Cu" "F.Mask" "F.Paste")
			(net "GND")
		)
		(pad "J48" smd circle
			(at 21.850096 -15.200122)
			(size 0.4572 0.4572)
			(layers "F.Cu" "F.Mask" "F.Paste")
			(net "GND")
		)
		(pad "J49" smd circle
			(at 22.800056 -15.200122)
			(size 0.4572 0.4572)
			(layers "F.Cu" "F.Mask" "F.Paste")
			(net "GND")
		)
		(pad "K1" smd circle
			(at -22.800056 -14.249908)
			(size 0.4572 0.4572)
			(layers "F.Cu" "F.Mask" "F.Paste")
			(net "P5E_PEX1_STN7_RX_DN<121>")
		)
		(pad "K2" smd circle
			(at -21.850096 -14.249908)
			(size 0.4572 0.4572)
			(layers "F.Cu" "F.Mask" "F.Paste")
			(net "P5E_PEX1_STN7_RX_DP<121>")
		)
		(pad "K3" smd circle
			(at -20.899882 -14.249908)
			(size 0.4572 0.4572)
			(layers "F.Cu" "F.Mask" "F.Paste")
			(net "GND")
		)
		(pad "K4" smd circle
			(at -19.949922 -14.249908)
			(size 0.4572 0.4572)
			(layers "F.Cu" "F.Mask" "F.Paste")
			(net "GND")
		)
		(pad "K5" smd circle
			(at -18.999962 -14.249908)
			(size 0.4572 0.4572)
			(layers "F.Cu" "F.Mask" "F.Paste")
			(net "GND")
		)
		(pad "K6" smd circle
			(at -18.050002 -14.249908)
			(size 0.4572 0.4572)
			(layers "F.Cu" "F.Mask" "F.Paste")
			(net "GND")
		)
		(pad "K7" smd circle
			(at -17.100042 -14.249908)
			(size 0.4572 0.4572)
			(layers "F.Cu" "F.Mask" "F.Paste")
			(net "GND")
		)
		(pad "K8" smd circle
			(at -16.150082 -14.249908)
			(size 0.4572 0.4572)
			(layers "F.Cu" "F.Mask" "F.Paste")
			(net "GND")
		)
		(pad "K9" smd circle
			(at -15.200122 -14.249908)
			(size 0.4572 0.4572)
			(layers "F.Cu" "F.Mask" "F.Paste")
			(net "GND")
		)
		(pad "K10" smd circle
			(at -14.249908 -14.249908)
			(size 0.4572 0.4572)
			(layers "F.Cu" "F.Mask" "F.Paste")
			(net "GND")
		)
		(pad "K11" smd circle
			(at -13.299948 -14.249908)
			(size 0.4572 0.4572)
			(layers "F.Cu" "F.Mask" "F.Paste")
			(net "GND")
		)
		(pad "K12" smd circle
			(at -12.349988 -14.249908)
			(size 0.4572 0.4572)
			(layers "F.Cu" "F.Mask" "F.Paste")
			(net "GND")
		)
		(pad "K13" smd circle
			(at -11.400028 -14.249908)
			(size 0.4572 0.4572)
			(layers "F.Cu" "F.Mask" "F.Paste")
			(net "GND")
		)
		(pad "K14" smd circle
			(at -10.450068 -14.249908)
			(size 0.4572 0.4572)
			(layers "F.Cu" "F.Mask" "F.Paste")
			(net "GND")
		)
		(pad "K15" smd circle
			(at -9.500108 -14.249908)
			(size 0.4572 0.4572)
			(layers "F.Cu" "F.Mask" "F.Paste")
			(net "GND")
		)
		(pad "K16" smd circle
			(at -8.549894 -14.249908)
			(size 0.4572 0.4572)
			(layers "F.Cu" "F.Mask" "F.Paste")
			(net "GND")
		)
		(pad "K17" smd circle
			(at -7.599934 -14.249908)
			(size 0.4572 0.4572)
			(layers "F.Cu" "F.Mask" "F.Paste")
			(net "GND")
		)
		(pad "K18" smd circle
			(at -6.649974 -14.249908)
			(size 0.4572 0.4572)
			(layers "F.Cu" "F.Mask" "F.Paste")
			(net "GND")
		)
		(pad "K19" smd circle
			(at -5.700014 -14.249908)
			(size 0.4572 0.4572)
			(layers "F.Cu" "F.Mask" "F.Paste")
			(net "GND")
		)
		(pad "K20" smd circle
			(at -4.750054 -14.249908)
			(size 0.4572 0.4572)
			(layers "F.Cu" "F.Mask" "F.Paste")
			(net "GND")
		)
		(pad "K21" smd circle
			(at -3.800094 -14.249908)
			(size 0.4572 0.4572)
			(layers "F.Cu" "F.Mask" "F.Paste")
			(net "GND")
		)
		(pad "K22" smd circle
			(at -2.84988 -14.249908)
			(size 0.4572 0.4572)
			(layers "F.Cu" "F.Mask" "F.Paste")
			(net "GND")
		)
		(pad "K23" smd circle
			(at -1.89992 -14.249908)
			(size 0.4572 0.4572)
			(layers "F.Cu" "F.Mask" "F.Paste")
			(net "GND")
		)
		(pad "K24" smd circle
			(at -0.94996 -14.249908)
			(size 0.4572 0.4572)
			(layers "F.Cu" "F.Mask" "F.Paste")
			(net "GND")
		)
	)
)
